FILE_TYPE=LIBRARY_PARTS;
primitive 'NCP698SQ15T1G';
  pin
    'GND':
      PIN_NUMBER='(1)';
      PINUSE='POWER';
      NO_LOAD_CHECK='Both';
      NO_IO_CHECK='Both';
      NO_ASSERT_CHECK='TRUE';
      NO_DIR_CHECK='TRUE';
      ALLOW_CONNECT='TRUE';
    'VOUT':
      PIN_NUMBER='(3)';
      OUTPUT_LOAD='(1.0,-1.0)';
    'VIN':
      PIN_NUMBER='(2)';
      INPUT_LOAD='(-0.01,0.01)';
    'EN':
      PIN_NUMBER='(4)';
      INPUT_LOAD='(-0.01,0.01)';
  end_pin;
  body
    PART_NAME='NCP698SQ15T1G';
    BODY_NAME='NCP698SQ15T1G';
    PHYS_DES_PREFIX='U';
    CLASS='IC';
  end_body;
end_primitive;

END.
